# T6G (Grand Teton) — schematic netlist excerpt (pin names and nets, part order shuffled) for the footprints in the layout excerpt that follows; sources: Cadence DE-HDL packaged netlist, KiCad conversion of 04192023_DAF0TMB3IC0_F0TG_MB_C_brd_V02_OCP.brd

J16  SCONN288_DDR506112002KQ  IO  pkg DDR288S_1-1VXC  page 92
  VIN_BULK0  = P12V_MEM_CPU0
  RFU0  = NC
  VIN_MGMT  = P3V3_AUX
  HSCL  = I3C_SPD_DDRG_CPU0_SCL
  HSDA  = I3C_SPD_DDRG_CPU0_SDA
  VSS0  = GND
  DQ0_A  = M_G_CPU0_SA_DQ<0>
  VSS1  = GND
  DQ1_A  = M_G_CPU0_SA_DQ<1>
  VSS2  = GND
  DQS0_A_T  = M_G_CPU0_SA_DQS_DP<0>
  DQS0_A_C  = M_G_CPU0_SA_DQS_DN<0>
  VSS3  = GND
  DQ4_A  = M_G_CPU0_SA_DQ<4>
  VSS4  = GND
  DQ5_A  = M_G_CPU0_SA_DQ<5>
  VSS5  = GND
  DQ8_A  = M_G_CPU0_SA_DQ<8>
  VSS6  = GND
  DQ9_A  = M_G_CPU0_SA_DQ<9>
  VSS7  = GND
  DQS1_A_T  = M_G_CPU0_SA_DQS_DP<1>
  DQS1_A_C  = M_G_CPU0_SA_DQS_DN<1>
  VSS8  = GND
  DQ12_A  = M_G_CPU0_SA_DQ<12>
  VSS9  = GND
  DQ13_A  = M_G_CPU0_SA_DQ<13>
  VSS10  = GND
  DQ16_A  = M_G_CPU0_SA_DQ<16>
  VSS11  = GND
  DQ17_A  = M_G_CPU0_SA_DQ<17>
  VSS12  = GND
  DQS2_A_T  = M_G_CPU0_SA_DQS_DP<2>
  DQS2_A_C  = M_G_CPU0_SA_DQS_DN<2>
  VSS13  = GND
  DQ20_A  = M_G_CPU0_SA_DQ<20>
  VSS14  = GND
  DQ21_A  = M_G_CPU0_SA_DQ<21>
  VSS15  = GND
  DQ24_A  = M_G_CPU0_SA_DQ<24>
  VSS16  = GND
  DQ25_A  = M_G_CPU0_SA_DQ<25>
  VSS17  = GND
  DQS3_A_T  = M_G_CPU0_SA_DQS_DP<3>
  DQS3_A_C  = M_G_CPU0_SA_DQS_DN<3>
  VSS18  = GND
  DQ28_A  = M_G_CPU0_SA_DQ<28>
  VSS19  = GND
  DQ29_A  = M_G_CPU0_SA_DQ<29>
  VSS20  = GND
  CB0_A  = M_G_CPU0_SA_CB<0>
  VSS21  = GND
  CB1_A  = M_G_CPU0_SA_CB<1>
  VSS22  = GND
  DQS4_A_T  = M_G_CPU0_SA_DQS_DP<4>
  DQS4_A_C  = M_G_CPU0_SA_DQS_DN<4>
  VSS23  = GND
  CB4_A  = M_G_CPU0_SA_CB<4>
  VSS24  = GND
  CB5_A  = M_G_CPU0_SA_CB<5>
  VSS25  = GND
  ALERT_N  = M_G_CPU0_ALERT_N
  VSS26  = GND
  CS0_A_N  = M_G_CPU0_SA_CS_N<0>
  VSS27  = GND
  CA0_A  = M_G_CPU0_SA_CA<0>
  VSS28  = GND
  CA2_A  = M_G_CPU0_SA_CA<2>
  VSS29  = GND
  CA4_A  = M_G_CPU0_SA_CA<4>
  VSS30  = GND
  CA6_A  = M_G_CPU0_SA_CA<6>
  VSS31  = GND
  PAR_A  = M_G_CPU0_SA_PAR
  VSS32  = GND
  CA0_B  = M_G_CPU0_SB_CA<0>
  VSS33  = GND
  CA2_B  = M_G_CPU0_SB_CA<2>
  VSS34  = GND
  CA4_B  = M_G_CPU0_SB_CA<4>
  VSS35  = GND
  CA6_B  = M_G_CPU0_SB_CA<6>
  VSS36  = GND
  CS0_B_N  = M_G_CPU0_SB_CS_N<0>
  VSS37  = GND
  \lbd||rsp_a_n\  = M_G_CPU0_SA_RSP<0>
  \lbs||rsp_b_n\  = M_G_CPU0_SB_RSP<0>
  VSS38  = GND
  CB4_B  = M_G_CPU0_SB_CB<4>
  VSS39  = GND
  CB5_B  = M_G_CPU0_SB_CB<5>
  VSS40  = GND
  \dqs9_b_t||tdqs9_b_t||dbi4_b_n\  = M_G_CPU0_SB_DQS_DP<9>
  \dqs9_b_c||tdqs9_b_c\  = M_G_CPU0_SB_DQS_DN<9>
  VSS41  = GND
  CB0_B  = M_G_CPU0_SB_CB<0>
  VSS42  = GND
  CB1_B  = M_G_CPU0_SB_CB<1>
  VSS43  = GND
  DQ0_B  = M_G_CPU0_SB_DQ<0>
  VSS44  = GND
  DQ1_B  = M_G_CPU0_SB_DQ<1>
  VSS45  = GND
  DQS0_B_T  = M_G_CPU0_SB_DQS_DP<0>
  DQS0_B_C  = M_G_CPU0_SB_DQS_DN<0>
  VSS46  = GND
  DQ4_B  = M_G_CPU0_SB_DQ<4>
  VSS47  = GND
  DQ5_B  = M_G_CPU0_SB_DQ<5>
  VSS48  = GND
  DQ8_B  = M_G_CPU0_SB_DQ<8>
  VSS49  = GND
  DQ9_B  = M_G_CPU0_SB_DQ<9>
  VSS50  = GND
  DQS1_B_T  = M_G_CPU0_SB_DQS_DP<1>
  DQS1_B_C  = M_G_CPU0_SB_DQS_DN<1>
  VSS51  = GND
  DQ12_B  = M_G_CPU0_SB_DQ<12>
  VSS52  = GND
  DQ13_B  = M_G_CPU0_SB_DQ<13>
  VSS53  = GND
  DQ16_B  = M_G_CPU0_SB_DQ<16>
  VSS54  = GND
  DQ17_B  = M_G_CPU0_SB_DQ<17>
  VSS55  = GND
  DQS2_B_T  = M_G_CPU0_SB_DQS_DP<2>
  DQS2_B_C  = M_G_CPU0_SB_DQS_DN<2>
  VSS56  = GND
  DQ20_B  = M_G_CPU0_SB_DQ<20>
  VSS57  = GND
  DQ21_B  = M_G_CPU0_SB_DQ<21>
  VSS58  = GND
  DQ24_B  = M_G_CPU0_SB_DQ<24>
  VSS59  = GND
  DQ25_B  = M_G_CPU0_SB_DQ<25>
  VSS60  = GND
  DQS3_B_T  = M_G_CPU0_SB_DQS_DP<3>
  DQS3_B_C  = M_G_CPU0_SB_DQS_DN<3>
  VSS61  = GND
  DQ28_B  = M_G_CPU0_SB_DQ<28>
  VSS62  = GND
  DQ29_B  = M_G_CPU0_SB_DQ<29>
  VSS63  = GND
  RFU1  = NC
  VIN_BULK1  = P12V_MEM_CPU0
  VIN_BULK2  = P12V_MEM_CPU0
  \pwr_good||fail_n\  = PWRGD_CHG_CPU0_DIMM0
  HAS  = PD_CHG_CPU0_DIMM0_SAA
  RFU2  = NC
  RFU3  = NC
  VSS64  = GND
  DQ2_A  = M_G_CPU0_SA_DQ<2>
  VSS65  = GND
  DQ3_A  = M_G_CPU0_SA_DQ<3>
  VSS66  = GND
  \dqs5_a_c||tdqs5_a_c||dqs5_a_t||tdqs5_a_t\  = M_G_CPU0_SA_DQS_DN<5>
  \dqs5_a_t||tdqs5_a_t\  = M_G_CPU0_SA_DQS_DP<5>
  VSS67  = GND
  DQ6_A  = M_G_CPU0_SA_DQ<6>
  VSS68  = GND
  DQ7_A  = M_G_CPU0_SA_DQ<7>
  VSS69  = GND
  DQ10_A  = M_G_CPU0_SA_DQ<10>
  VSS70  = GND
  DQ11_A  = M_G_CPU0_SA_DQ<11>
  VSS71  = GND
  \dqs6_a_c||tdqs6_a_c||dqs6_a_t||tdqs6_a_t\  = M_G_CPU0_SA_DQS_DN<6>
  \dqs6_a_t||tdqs6_a_t\  = M_G_CPU0_SA_DQS_DP<6>
  VSS72  = GND
  DQ14_A  = M_G_CPU0_SA_DQ<14>
  VSS73  = GND
  DQ15_A  = M_G_CPU0_SA_DQ<15>
  VSS74  = GND
  DQ18_A  = M_G_CPU0_SA_DQ<18>
  VSS75  = GND
  DQ19_A  = M_G_CPU0_SA_DQ<19>
  VSS76  = GND
  \dqs7_a_c||tdqs7_a_c\  = M_G_CPU0_SA_DQS_DN<7>
  \dqs7_a_t||tdqs7_a_t\  = M_G_CPU0_SA_DQS_DP<7>
  VSS77  = GND
  DQ22_A  = M_G_CPU0_SA_DQ<22>
  VSS78  = GND
  DQ23_A  = M_G_CPU0_SA_DQ<23>
  VSS79  = GND
  DQ26_A  = M_G_CPU0_SA_DQ<26>
  VSS80  = GND
  DQ27_A  = M_G_CPU0_SA_DQ<27>
  VSS81  = GND
  \dqs8_a_c||tdqs8_a_c\  = M_G_CPU0_SA_DQS_DN<8>
  \dqs8_a_t||tdqs8_a_t\  = M_G_CPU0_SA_DQS_DP<8>
  VSS82  = GND
  DQ30_A  = M_G_CPU0_SA_DQ<30>
  VSS83  = GND
  DQ31_A  = M_G_CPU0_SA_DQ<31>
  VSS84  = GND
  CB2_A  = M_G_CPU0_SA_CB<2>
  VSS85  = GND
  CB3_A  = M_G_CPU0_SA_CB<3>
  VSS86  = GND
  \dqs9_a_c||tdqs9_a_c\  = M_G_CPU0_SA_DQS_DN<9>
  \dqs9_a_t||tdqs9_a_t\  = M_G_CPU0_SA_DQS_DP<9>
  VSS87  = GND
  CB6_A  = M_G_CPU0_SA_CB<6>
  VSS88  = GND
  CB7_A  = M_G_CPU0_SA_CB<7>
  VSS89  = GND
  RESET_N  = M_G_CPU0_RESET_N
  VSS90  = GND
  CS1_A_N  = M_G_CPU0_SA_CS_N<1>
  VSS91  = GND
  CA1_A  = M_G_CPU0_SA_CA<1>
  VSS92  = GND
  CA3_A  = M_G_CPU0_SA_CA<3>
  VSS93  = GND
  CA5_A  = M_G_CPU0_SA_CA<5>
  VSS94  = GND
  CK_T  = M_G_CPU0_CLK_DP<0>
  CK_C  = M_G_CPU0_CLK_DN<0>
  VSS95  = GND
  RFU4  = NC
  CA1_B  = M_G_CPU0_SB_CA<1>
  VSS96  = GND
  CA3_B  = M_G_CPU0_SB_CA<3>
  VSS97  = GND
  CA5_B  = M_G_CPU0_SB_CA<5>
  VSS98  = GND
  PAR_B  = M_G_CPU0_SB_PAR
  VSS99  = GND
  CS1_B_N  = M_G_CPU0_SB_CS_N<1>
  VSS100  = GND
  RFU5  = NC
  RFU6  = NC
  VSS101  = GND
  CB6_B  = M_G_CPU0_SB_CB<6>
  VSS102  = GND
  CB7_B  = M_G_CPU0_SB_CB<7>
  VSS103  = GND
  DQS4_B_C  = M_G_CPU0_SB_DQS_DN<4>
  DQS4_B_T  = M_G_CPU0_SB_DQS_DP<4>
  VSS104  = GND
  CB2_B  = M_G_CPU0_SB_CB<2>
  VSS105  = GND
  CB3_B  = M_G_CPU0_SB_CB<3>
  VSS106  = GND
  DQ2_B  = M_G_CPU0_SB_DQ<2>
  VSS107  = GND
  DQ3_B  = M_G_CPU0_SB_DQ<3>
  VSS108  = GND
  \dqs5_b_c||tdqs5_b_c\  = M_G_CPU0_SB_DQS_DN<5>
  \dqs5_b_t||tdqs5_b_t\  = M_G_CPU0_SB_DQS_DP<5>
  VSS109  = GND
  DQ6_B  = M_G_CPU0_SB_DQ<6>
  VSS110  = GND
  DQ7_B  = M_G_CPU0_SB_DQ<7>
  VSS111  = GND
  DQ10_B  = M_G_CPU0_SB_DQ<10>
  VSS112  = GND
  DQ11_B  = M_G_CPU0_SB_DQ<11>
  VSS113  = GND
  \dqs6_b_c||tdqs6_b_c\  = M_G_CPU0_SB_DQS_DN<6>
  \dqs6_b_t||tdqs6_b_t\  = M_G_CPU0_SB_DQS_DP<6>
  VSS114  = GND
  DQ14_B  = M_G_CPU0_SB_DQ<14>
  VSS115  = GND
  DQ15_B  = M_G_CPU0_SB_DQ<15>
  VSS116  = GND
  DQ18_B  = M_G_CPU0_SB_DQ<18>
  VSS117  = GND
  DQ19_B  = M_G_CPU0_SB_DQ<19>
  VSS118  = GND
  \dqs7_b_c||tdqs7_b_c\  = M_G_CPU0_SB_DQS_DN<7>
  \dqs7_b_t||tdqs7_b_t\  = M_G_CPU0_SB_DQS_DP<7>
  VSS119  = GND
  DQ22_B  = M_G_CPU0_SB_DQ<22>
  VSS120  = GND
  DQ23_B  = M_G_CPU0_SB_DQ<23>
  VSS121  = GND
  DQ26_B  = M_G_CPU0_SB_DQ<26>
  VSS122  = GND
  DQ27_B  = M_G_CPU0_SB_DQ<27>
  VSS123  = GND
  \dqs8_b_c||tdqs8_b_c\  = M_G_CPU0_SB_DQS_DN<8>
  \dqs8_b_t||tdqs8_b_t\  = M_G_CPU0_SB_DQS_DP<8>
  VSS124  = GND
  DQ30_B  = M_G_CPU0_SB_DQ<30>
  VSS125  = GND
  DQ31_B  = M_G_CPU0_SB_DQ<31>
  VSS126  = GND
  G1  = GND
  G2  = GND
  G3  = GND

(kicad_pcb
	(version 20260206)
	(generator "pcbnew")
	(generator_version "10.0")
	(general
		(thickness 1.6)
		(legacy_teardrops no)
	)
	(paper "A4")
	(title_block
		(title "04192023_DAF0TMB3IC0_F0TG_MB_C_brd_V02_OCP.brd")
		(comment 1 "Grand Teton / footprint 1808 of 8354 (J16), pads 139-184 of 291")
	)
	(layers
		(0 "F.Cu" signal "TOP")
		(4 "In1.Cu" signal "GND")
		(6 "In2.Cu" signal "IN1")
		(8 "In3.Cu" signal "GND1")
		(10 "In4.Cu" signal "IN2")
		(12 "In5.Cu" signal "GND2")
		(14 "In6.Cu" signal "IN3")
		(16 "In7.Cu" signal "GND3")
		(18 "In8.Cu" signal "VCC")
		(20 "In9.Cu" signal "VCC1")
		(22 "In10.Cu" signal "GND4")
		(24 "In11.Cu" signal "IN4")
		(26 "In12.Cu" signal "GND5")
		(28 "In13.Cu" signal "IN5")
		(30 "In14.Cu" signal "GND6")
		(32 "In15.Cu" signal "IN6")
		(34 "In16.Cu" signal "GND7")
		(2 "B.Cu" signal "BOTTOM")
		(9 "F.Adhes" user "F.Adhesive")
		(11 "B.Adhes" user "B.Adhesive")
		(13 "F.Paste" user "Package Geometry/Pastemask Top")
		(15 "B.Paste" user "Package Geometry/Pastemask Bottom")
		(5 "F.SilkS" user "Ref Des/Silkscreen Top")
		(7 "B.SilkS" user "Ref Des/Silkscreen Bottom")
		(1 "F.Mask" user "Board Geometry/Soldermask Top")
		(3 "B.Mask" user "Board Geometry/Soldermask Bottom")
		(17 "Dwgs.User" user "User.Drawings")
		(19 "Cmts.User" user "User.Comments")
		(21 "Eco1.User" user "User.Eco1")
		(23 "Eco2.User" user "User.Eco2")
		(25 "Edge.Cuts" user "Board Geometry/Outline")
		(27 "Margin" user)
		(31 "F.CrtYd" user "Package Geometry/Place Bound Top")
		(29 "B.CrtYd" user "Package Geometry/Place Bound Bottom")
		(35 "F.Fab" user "Ref Des/Assembly Top")
		(33 "B.Fab" user "Ref Des/Assembly Bottom")
	)
	(footprint ""
		(layer "F.Cu")
		(at 414.418018 -255.560068 180)
		(property "Reference" "J16"
			(at 1.474216 81.889092 0)
			(unlocked yes)
			(layer "F.SilkS")
			(effects
				(font
					(size 0.7874 0.5842)
					(thickness 0.1524)
				)
			)
		)
		(property "Value" ""
			(at 0 0 180)
			(layer "F.Fab")
			(effects
				(font
					(size 1.27 1.27)
				)
			)
		)
		(duplicate_pad_numbers_are_jumpers no)
		(pad "139" smd rect
			(at -2.050034 59.075066 90)
			(size 0.519938 1.4986)
			(layers "F.Cu" "F.Mask" "F.Paste")
			(net "GND")
		)
		(pad "140" smd rect
			(at -2.050034 59.92495 90)
			(size 0.519938 1.4986)
			(layers "F.Cu" "F.Mask" "F.Paste")
			(net "M_G_CPU0_SB_DQ<28>")
		)
		(pad "141" smd rect
			(at -2.050034 60.775088 90)
			(size 0.519938 1.4986)
			(layers "F.Cu" "F.Mask" "F.Paste")
			(net "GND")
		)
		(pad "142" smd rect
			(at -2.050034 61.624972 90)
			(size 0.519938 1.4986)
			(layers "F.Cu" "F.Mask" "F.Paste")
			(net "M_G_CPU0_SB_DQ<29>")
		)
		(pad "143" smd rect
			(at -2.050034 62.47511 90)
			(size 0.519938 1.4986)
			(layers "F.Cu" "F.Mask" "F.Paste")
			(net "GND")
		)
		(pad "144" smd rect
			(at -2.050034 63.324994 90)
			(size 0.519938 1.4986)
			(layers "F.Cu" "F.Mask" "F.Paste")
			(net "Net_2334")
		)
		(pad "145" smd rect
			(at 2.050034 -63.324994 90)
			(size 0.519938 1.4986)
			(layers "F.Cu" "F.Mask" "F.Paste")
			(net "P12V_MEM_CPU0")
		)
		(pad "146" smd rect
			(at 2.050034 -62.47511 90)
			(size 0.519938 1.4986)
			(layers "F.Cu" "F.Mask" "F.Paste")
			(net "P12V_MEM_CPU0")
		)
		(pad "147" smd rect
			(at 2.050034 -61.624972 90)
			(size 0.519938 1.4986)
			(layers "F.Cu" "F.Mask" "F.Paste")
			(net "PWRGD_CHG_CPU0_DIMM0")
		)
		(pad "148" smd rect
			(at 2.050034 -60.775088 90)
			(size 0.519938 1.4986)
			(layers "F.Cu" "F.Mask" "F.Paste")
			(net "PD_CHG_CPU0_DIMM0_SAA")
		)
		(pad "149" smd rect
			(at 2.050034 -59.92495 90)
			(size 0.519938 1.4986)
			(layers "F.Cu" "F.Mask" "F.Paste")
			(net "Net_2335")
		)
		(pad "150" smd rect
			(at 2.050034 -59.075066 90)
			(size 0.519938 1.4986)
			(layers "F.Cu" "F.Mask" "F.Paste")
			(net "Net_2336")
		)
		(pad "151" smd rect
			(at 2.050034 -58.224928 90)
			(size 0.519938 1.4986)
			(layers "F.Cu" "F.Mask" "F.Paste")
			(net "GND")
		)
		(pad "152" smd rect
			(at 2.050034 -57.375044 90)
			(size 0.519938 1.4986)
			(layers "F.Cu" "F.Mask" "F.Paste")
			(net "M_G_CPU0_SA_DQ<2>")
		)
		(pad "153" smd rect
			(at 2.050034 -56.524906 90)
			(size 0.519938 1.4986)
			(layers "F.Cu" "F.Mask" "F.Paste")
			(net "GND")
		)
		(pad "154" smd rect
			(at 2.050034 -55.675022 90)
			(size 0.519938 1.4986)
			(layers "F.Cu" "F.Mask" "F.Paste")
			(net "M_G_CPU0_SA_DQ<3>")
		)
		(pad "155" smd rect
			(at 2.050034 -54.824884 90)
			(size 0.519938 1.4986)
			(layers "F.Cu" "F.Mask" "F.Paste")
			(net "GND")
		)
		(pad "156" smd rect
			(at 2.050034 -53.975 90)
			(size 0.519938 1.4986)
			(layers "F.Cu" "F.Mask" "F.Paste")
			(net "M_G_CPU0_SA_DQS_DN<5>")
		)
		(pad "157" smd rect
			(at 2.050034 -53.125116 90)
			(size 0.519938 1.4986)
			(layers "F.Cu" "F.Mask" "F.Paste")
			(net "M_G_CPU0_SA_DQS_DP<5>")
		)
		(pad "158" smd rect
			(at 2.050034 -52.274978 90)
			(size 0.519938 1.4986)
			(layers "F.Cu" "F.Mask" "F.Paste")
			(net "GND")
		)
		(pad "159" smd rect
			(at 2.050034 -51.425094 90)
			(size 0.519938 1.4986)
			(layers "F.Cu" "F.Mask" "F.Paste")
			(net "M_G_CPU0_SA_DQ<6>")
		)
		(pad "160" smd rect
			(at 2.050034 -50.574956 90)
			(size 0.519938 1.4986)
			(layers "F.Cu" "F.Mask" "F.Paste")
			(net "GND")
		)
		(pad "161" smd rect
			(at 2.050034 -49.725072 90)
			(size 0.519938 1.4986)
			(layers "F.Cu" "F.Mask" "F.Paste")
			(net "M_G_CPU0_SA_DQ<7>")
		)
		(pad "162" smd rect
			(at 2.050034 -48.874934 90)
			(size 0.519938 1.4986)
			(layers "F.Cu" "F.Mask" "F.Paste")
			(net "GND")
		)
		(pad "163" smd rect
			(at 2.050034 -48.02505 90)
			(size 0.519938 1.4986)
			(layers "F.Cu" "F.Mask" "F.Paste")
			(net "M_G_CPU0_SA_DQ<10>")
		)
		(pad "164" smd rect
			(at 2.050034 -47.174912 90)
			(size 0.519938 1.4986)
			(layers "F.Cu" "F.Mask" "F.Paste")
			(net "GND")
		)
		(pad "165" smd rect
			(at 2.050034 -46.325028 90)
			(size 0.519938 1.4986)
			(layers "F.Cu" "F.Mask" "F.Paste")
			(net "M_G_CPU0_SA_DQ<11>")
		)
		(pad "166" smd rect
			(at 2.050034 -45.47489 90)
			(size 0.519938 1.4986)
			(layers "F.Cu" "F.Mask" "F.Paste")
			(net "GND")
		)
		(pad "167" smd rect
			(at 2.050034 -44.625006 90)
			(size 0.519938 1.4986)
			(layers "F.Cu" "F.Mask" "F.Paste")
			(net "M_G_CPU0_SA_DQS_DN<6>")
		)
		(pad "168" smd rect
			(at 2.050034 -43.775122 90)
			(size 0.519938 1.4986)
			(layers "F.Cu" "F.Mask" "F.Paste")
			(net "M_G_CPU0_SA_DQS_DP<6>")
		)
		(pad "169" smd rect
			(at 2.050034 -42.924984 90)
			(size 0.519938 1.4986)
			(layers "F.Cu" "F.Mask" "F.Paste")
			(net "GND")
		)
		(pad "170" smd rect
			(at 2.050034 -42.0751 90)
			(size 0.519938 1.4986)
			(layers "F.Cu" "F.Mask" "F.Paste")
			(net "M_G_CPU0_SA_DQ<14>")
		)
		(pad "171" smd rect
			(at 2.050034 -41.224962 90)
			(size 0.519938 1.4986)
			(layers "F.Cu" "F.Mask" "F.Paste")
			(net "GND")
		)
		(pad "172" smd rect
			(at 2.050034 -40.375078 90)
			(size 0.519938 1.4986)
			(layers "F.Cu" "F.Mask" "F.Paste")
			(net "M_G_CPU0_SA_DQ<15>")
		)
		(pad "173" smd rect
			(at 2.050034 -39.52494 90)
			(size 0.519938 1.4986)
			(layers "F.Cu" "F.Mask" "F.Paste")
			(net "GND")
		)
		(pad "174" smd rect
			(at 2.050034 -38.675056 90)
			(size 0.519938 1.4986)
			(layers "F.Cu" "F.Mask" "F.Paste")
			(net "M_G_CPU0_SA_DQ<18>")
		)
		(pad "175" smd rect
			(at 2.050034 -37.824918 90)
			(size 0.519938 1.4986)
			(layers "F.Cu" "F.Mask" "F.Paste")
			(net "GND")
		)
		(pad "176" smd rect
			(at 2.050034 -36.975034 90)
			(size 0.519938 1.4986)
			(layers "F.Cu" "F.Mask" "F.Paste")
			(net "M_G_CPU0_SA_DQ<19>")
		)
		(pad "177" smd rect
			(at 2.050034 -36.124896 90)
			(size 0.519938 1.4986)
			(layers "F.Cu" "F.Mask" "F.Paste")
			(net "GND")
		)
		(pad "178" smd rect
			(at 2.050034 -35.275012 90)
			(size 0.519938 1.4986)
			(layers "F.Cu" "F.Mask" "F.Paste")
			(net "M_G_CPU0_SA_DQS_DN<7>")
		)
		(pad "179" smd rect
			(at 2.050034 -34.425128 90)
			(size 0.519938 1.4986)
			(layers "F.Cu" "F.Mask" "F.Paste")
			(net "M_G_CPU0_SA_DQS_DP<7>")
		)
		(pad "180" smd rect
			(at 2.050034 -33.57499 90)
			(size 0.519938 1.4986)
			(layers "F.Cu" "F.Mask" "F.Paste")
			(net "GND")
		)
		(pad "181" smd rect
			(at 2.050034 -32.725106 90)
			(size 0.519938 1.4986)
			(layers "F.Cu" "F.Mask" "F.Paste")
			(net "M_G_CPU0_SA_DQ<22>")
		)
		(pad "182" smd rect
			(at 2.050034 -31.874968 90)
			(size 0.519938 1.4986)
			(layers "F.Cu" "F.Mask" "F.Paste")
			(net "GND")
		)
		(pad "183" smd rect
			(at 2.050034 -31.025084 90)
			(size 0.519938 1.4986)
			(layers "F.Cu" "F.Mask" "F.Paste")
			(net "M_G_CPU0_SA_DQ<23>")
		)
		(pad "184" smd rect
			(at 2.050034 -30.174946 90)
			(size 0.519938 1.4986)
			(layers "F.Cu" "F.Mask" "F.Paste")
			(net "GND")
		)
	)
)
